(kicad_pcb
	(version 20260206)
	(generator "pcbnew")
	(generator_version "10.0")
	(general
		(thickness 1.6)
		(legacy_teardrops no)
	)
	(paper "A4")
	(title_block
		(title "Bryce Canyon_SCC_16316-1_OCP.brd")
		(comment 1 "Bryce Canyon / footprints 1113-1119 of 1561")
	)
	(layers
		(0 "F.Cu" signal "TOP")
		(4 "In1.Cu" signal "L2GND")
		(6 "In2.Cu" signal "L3")
		(8 "In3.Cu" signal "L4VCC")
		(10 "In4.Cu" signal "L5VCC")
		(12 "In5.Cu" signal "L6")
		(14 "In6.Cu" signal "L7GND")
		(2 "B.Cu" signal "BOTTOM")
		(9 "F.Adhes" user "F.Adhesive")
		(11 "B.Adhes" user "B.Adhesive")
		(13 "F.Paste" user "Package Geometry/Pastemask Top")
		(15 "B.Paste" user "Package Geometry/Pastemask Bottom")
		(5 "F.SilkS" user "Ref Des/Silkscreen Top")
		(7 "B.SilkS" user "Ref Des/Silkscreen Bottom")
		(1 "F.Mask" user "Board Geometry/Soldermask Top")
		(3 "B.Mask" user "Board Geometry/Soldermask Bottom")
		(17 "Dwgs.User" user "User.Drawings")
		(19 "Cmts.User" user "User.Comments")
		(21 "Eco1.User" user "User.Eco1")
		(23 "Eco2.User" user "User.Eco2")
		(25 "Edge.Cuts" user "Board Geometry/Outline")
		(27 "Margin" user)
		(31 "F.CrtYd" user "Package Geometry/Place Bound Top")
		(29 "B.CrtYd" user "Package Geometry/Place Bound Bottom")
		(35 "F.Fab" user "Ref Des/Assembly Top")
		(33 "B.Fab" user "Ref Des/Assembly Bottom")
	)
	(footprint ""
		(layer "B.Cu")
		(at 173.659292 -35.56127)
		(property "Reference" "C438"
			(at 0 0 0)
			(layer "B.SilkS")
			(hide yes)
			(effects
				(font
					(size 1.27 1.27)
				)
				(justify mirror)
			)
		)
		(property "Value" "SCD1U6D3V1KX-GP"
			(at 2.8321 -1.7399 0)
			(unlocked yes)
			(layer "B.Fab")
			(hide yes)
			(effects
				(font
					(size 1.016 1.016)
					(thickness 0.1524)
				)
				(justify mirror)
			)
		)
		(property "Device Type" "C0201H13"
			(at 2.8321 -3.2639 0)
			(unlocked yes)
			(layer "B.Fab")
			(hide yes)
			(effects
				(font
					(size 1.016 1.016)
					(thickness 0.1524)
				)
				(justify mirror)
			)
		)
		(duplicate_pad_numbers_are_jumpers no)
		(fp_rect
			(start 0.2794 0.6477)
			(end -0.2794 -0.6477)
			(stroke
				(width 0)
				(type default)
			)
			(fill no)
			(layer "B.CrtYd")
		)
		(fp_rect
			(start 0.2794 0.6477)
			(end -0.2794 -0.6477)
			(stroke
				(width 0)
				(type default)
			)
			(fill no)
			(layer "B.Fab")
		)
		(pad "1" smd custom
			(at 0 -0.2794 180)
			(size 0.0762 0.0762)
			(layers "B.Cu" "B.Mask" "B.Paste")
			(net "P0V975")
			(options
				(clearance outline)
				(anchor circle)
			)
			(primitives
				(gr_poly
					(pts
						(arc
							(start 0.1524 0.127)
							(mid 0.137521 0.162921)
							(end 0.1016 0.1778)
						)
						(arc
							(start -0.1016 0.1778)
							(mid -0.137521 0.162921)
							(end -0.1524 0.127)
						)
						(arc
							(start -0.1524 -0.127)
							(mid -0.137521 -0.162921)
							(end -0.1016 -0.1778)
						)
						(arc
							(start 0.1016 -0.1778)
							(mid 0.137521 -0.162921)
							(end 0.1524 -0.127)
						)
					)
					(width 0)
					(fill yes)
				)
			)
		)
		(pad "2" smd custom
			(at 0 0.2794 180)
			(size 0.0762 0.0762)
			(layers "B.Cu" "B.Mask" "B.Paste")
			(net "GND")
			(options
				(clearance outline)
				(anchor circle)
			)
			(primitives
				(gr_poly
					(pts
						(arc
							(start 0.1524 0.127)
							(mid 0.137521 0.162921)
							(end 0.1016 0.1778)
						)
						(arc
							(start -0.1016 0.1778)
							(mid -0.137521 0.162921)
							(end -0.1524 0.127)
						)
						(arc
							(start -0.1524 -0.127)
							(mid -0.137521 -0.162921)
							(end -0.1016 -0.1778)
						)
						(arc
							(start 0.1016 -0.1778)
							(mid 0.137521 -0.162921)
							(end 0.1524 -0.127)
						)
					)
					(width 0)
					(fill yes)
				)
			)
		)
	)
	(footprint ""
		(layer "B.Cu")
		(at 112.7506 -59.4487)
		(property "Reference" "C247"
			(at 0 0 0)
			(layer "B.SilkS")
			(hide yes)
			(effects
				(font
					(size 1.27 1.27)
				)
				(justify mirror)
			)
		)
		(property "Value" "SCD1U6D3V1KX-GP"
			(at 2.8321 -1.7399 0)
			(unlocked yes)
			(layer "B.Fab")
			(hide yes)
			(effects
				(font
					(size 1.016 1.016)
					(thickness 0.1524)
				)
				(justify mirror)
			)
		)
		(property "Device Type" "C0201H13"
			(at 2.8321 -3.2639 0)
			(unlocked yes)
			(layer "B.Fab")
			(hide yes)
			(effects
				(font
					(size 1.016 1.016)
					(thickness 0.1524)
				)
				(justify mirror)
			)
		)
		(duplicate_pad_numbers_are_jumpers no)
		(fp_rect
			(start 0.2794 0.6477)
			(end -0.2794 -0.6477)
			(stroke
				(width 0)
				(type default)
			)
			(fill no)
			(layer "B.CrtYd")
		)
		(fp_rect
			(start 0.2794 0.6477)
			(end -0.2794 -0.6477)
			(stroke
				(width 0)
				(type default)
			)
			(fill no)
			(layer "B.Fab")
		)
		(pad "1" smd custom
			(at 0 -0.2794 180)
			(size 0.0762 0.0762)
			(layers "B.Cu" "B.Mask" "B.Paste")
			(net "GB_VDDA")
			(options
				(clearance outline)
				(anchor circle)
			)
			(primitives
				(gr_poly
					(pts
						(arc
							(start 0.1524 0.127)
							(mid 0.137521 0.162921)
							(end 0.1016 0.1778)
						)
						(arc
							(start -0.1016 0.1778)
							(mid -0.137521 0.162921)
							(end -0.1524 0.127)
						)
						(arc
							(start -0.1524 -0.127)
							(mid -0.137521 -0.162921)
							(end -0.1016 -0.1778)
						)
						(arc
							(start 0.1016 -0.1778)
							(mid 0.137521 -0.162921)
							(end 0.1524 -0.127)
						)
					)
					(width 0)
					(fill yes)
				)
			)
		)
		(pad "2" smd custom
			(at 0 0.2794 180)
			(size 0.0762 0.0762)
			(layers "B.Cu" "B.Mask" "B.Paste")
			(net "GND")
			(options
				(clearance outline)
				(anchor circle)
			)
			(primitives
				(gr_poly
					(pts
						(arc
							(start 0.1524 0.127)
							(mid 0.137521 0.162921)
							(end 0.1016 0.1778)
						)
						(arc
							(start -0.1016 0.1778)
							(mid -0.137521 0.162921)
							(end -0.1524 0.127)
						)
						(arc
							(start -0.1524 -0.127)
							(mid -0.137521 -0.162921)
							(end -0.1016 -0.1778)
						)
						(arc
							(start 0.1016 -0.1778)
							(mid 0.137521 -0.162921)
							(end 0.1524 -0.127)
						)
					)
					(width 0)
					(fill yes)
				)
			)
		)
	)
	(footprint ""
		(layer "B.Cu")
		(at 201.803 -35.3314)
		(property "Reference" "R201"
			(at 0 0 0)
			(layer "B.SilkS")
			(hide yes)
			(effects
				(font
					(size 1.27 1.27)
				)
				(justify mirror)
			)
		)
		(property "Value" "4K7R2F-GP"
			(at -0.064008 -3.993896 0)
			(unlocked yes)
			(layer "B.Fab")
			(hide yes)
			(effects
				(font
					(size 1.016 1.016)
					(thickness 0.1524)
				)
				(justify mirror)
			)
		)
		(property "Device Type" "R402H16"
			(at -0.064008 -5.517896 0)
			(unlocked yes)
			(layer "B.Fab")
			(hide yes)
			(effects
				(font
					(size 1.016 1.016)
					(thickness 0.1524)
				)
				(justify mirror)
			)
		)
		(duplicate_pad_numbers_are_jumpers no)
		(fp_line
			(start -0.508 -0.9398)
			(end 0.508 -0.9398)
			(stroke
				(width 0.1524)
				(type default)
			)
			(layer "B.SilkS")
		)
		(fp_line
			(start 0.508 -0.9398)
			(end 0.508 0.9398)
			(stroke
				(width 0.1524)
				(type default)
			)
			(layer "B.SilkS")
		)
		(fp_rect
			(start 0.508 0.9398)
			(end -0.508 -0.9398)
			(stroke
				(width 0)
				(type default)
			)
			(fill no)
			(layer "B.CrtYd")
		)
		(fp_rect
			(start 0.508 0.9398)
			(end -0.508 -0.9398)
			(stroke
				(width 0)
				(type default)
			)
			(fill no)
			(layer "B.Fab")
		)
		(pad "1" smd custom
			(at 0 -0.4445 180)
			(size 0.1397 0.1397)
			(layers "B.Cu" "B.Mask" "B.Paste")
			(net "IOC_EEPROM_A1")
			(options
				(clearance outline)
				(anchor circle)
			)
			(primitives
				(gr_poly
					(pts
						(arc
							(start -0.1778 0.2794)
							(mid -0.249642 0.249642)
							(end -0.2794 0.1778)
						)
						(arc
							(start -0.2794 -0.1778)
							(mid -0.249642 -0.249642)
							(end -0.1778 -0.2794)
						)
						(arc
							(start 0.1778 -0.2794)
							(mid 0.249642 -0.249642)
							(end 0.2794 -0.1778)
						)
						(arc
							(start 0.2794 0.1778)
							(mid 0.249642 0.249642)
							(end 0.1778 0.2794)
						)
					)
					(width 0)
					(fill yes)
				)
			)
		)
		(pad "2" smd custom
			(at 0 0.4445 180)
			(size 0.1397 0.1397)
			(layers "B.Cu" "B.Mask" "B.Paste")
			(net "GND")
			(options
				(clearance outline)
				(anchor circle)
			)
			(primitives
				(gr_poly
					(pts
						(arc
							(start -0.1778 0.2794)
							(mid -0.249642 0.249642)
							(end -0.2794 0.1778)
						)
						(arc
							(start -0.2794 -0.1778)
							(mid -0.249642 -0.249642)
							(end -0.1778 -0.2794)
						)
						(arc
							(start 0.1778 -0.2794)
							(mid 0.249642 -0.249642)
							(end 0.2794 -0.1778)
						)
						(arc
							(start 0.2794 0.1778)
							(mid 0.249642 0.249642)
							(end 0.1778 0.2794)
						)
					)
					(width 0)
					(fill yes)
				)
			)
		)
	)
	(footprint ""
		(layer "B.Cu")
		(at 163.8173 -9.779 180)
		(property "Reference" "C735"
			(at 0 0 0)
			(layer "B.SilkS")
			(hide yes)
			(effects
				(font
					(size 1.27 1.27)
				)
				(justify mirror)
			)
		)
		(property "Value" "SCD1U16V2KX-3GP"
			(at -1.1811 -2.7051 180)
			(unlocked yes)
			(layer "B.Fab")
			(hide yes)
			(effects
				(font
					(size 1.016 1.016)
					(thickness 0.1524)
				)
				(justify mirror)
			)
		)
		(property "Device Type" "C402H22"
			(at -1.1811 -4.2291 180)
			(unlocked yes)
			(layer "B.Fab")
			(hide yes)
			(effects
				(font
					(size 1.016 1.016)
					(thickness 0.1524)
				)
				(justify mirror)
			)
		)
		(duplicate_pad_numbers_are_jumpers no)
		(fp_rect
			(start 0.4318 0.9525)
			(end -0.4318 -0.9525)
			(stroke
				(width 0)
				(type default)
			)
			(fill no)
			(layer "B.CrtYd")
		)
		(fp_rect
			(start 0.4318 0.9525)
			(end -0.4318 -0.9525)
			(stroke
				(width 0)
				(type default)
			)
			(fill no)
			(layer "B.Fab")
		)
		(pad "1" smd custom
			(at 0 -0.4445)
			(size 0.1524 0.1524)
			(layers "B.Cu" "B.Mask" "B.Paste")
			(net "P3V3")
			(options
				(clearance outline)
				(anchor circle)
			)
			(primitives
				(gr_poly
					(pts
						(arc
							(start 0.3048 0.2032)
							(mid 0.275042 0.275042)
							(end 0.2032 0.3048)
						)
						(arc
							(start -0.2032 0.3048)
							(mid -0.275042 0.275042)
							(end -0.3048 0.2032)
						)
						(arc
							(start -0.3048 -0.2032)
							(mid -0.275042 -0.275042)
							(end -0.2032 -0.3048)
						)
						(arc
							(start 0.2032 -0.3048)
							(mid 0.275042 -0.275042)
							(end 0.3048 -0.2032)
						)
					)
					(width 0)
					(fill yes)
				)
			)
		)
		(pad "2" smd custom
			(at 0 0.4445)
			(size 0.1524 0.1524)
			(layers "B.Cu" "B.Mask" "B.Paste")
			(net "GND")
			(options
				(clearance outline)
				(anchor circle)
			)
			(primitives
				(gr_poly
					(pts
						(arc
							(start 0.3048 0.2032)
							(mid 0.275042 0.275042)
							(end 0.2032 0.3048)
						)
						(arc
							(start -0.2032 0.3048)
							(mid -0.275042 0.275042)
							(end -0.3048 0.2032)
						)
						(arc
							(start -0.3048 -0.2032)
							(mid -0.275042 -0.275042)
							(end -0.2032 -0.3048)
						)
						(arc
							(start 0.2032 -0.3048)
							(mid 0.275042 -0.275042)
							(end 0.3048 -0.2032)
						)
					)
					(width 0)
					(fill yes)
				)
			)
		)
	)
	(footprint ""
		(layer "B.Cu")
		(at 112.6236 -66.3575)
		(property "Reference" "C169"
			(at 0 0 0)
			(layer "B.SilkS")
			(hide yes)
			(effects
				(font
					(size 1.27 1.27)
				)
				(justify mirror)
			)
		)
		(property "Value" "SCD1U6D3V1KX-GP"
			(at 2.8321 -1.7399 0)
			(unlocked yes)
			(layer "B.Fab")
			(hide yes)
			(effects
				(font
					(size 1.016 1.016)
					(thickness 0.1524)
				)
				(justify mirror)
			)
		)
		(property "Device Type" "C0201H13"
			(at 2.8321 -3.2639 0)
			(unlocked yes)
			(layer "B.Fab")
			(hide yes)
			(effects
				(font
					(size 1.016 1.016)
					(thickness 0.1524)
				)
				(justify mirror)
			)
		)
		(duplicate_pad_numbers_are_jumpers no)
		(fp_rect
			(start 0.2794 0.6477)
			(end -0.2794 -0.6477)
			(stroke
				(width 0)
				(type default)
			)
			(fill no)
			(layer "B.CrtYd")
		)
		(fp_rect
			(start 0.2794 0.6477)
			(end -0.2794 -0.6477)
			(stroke
				(width 0)
				(type default)
			)
			(fill no)
			(layer "B.Fab")
		)
		(pad "1" smd custom
			(at 0 -0.2794 180)
			(size 0.0762 0.0762)
			(layers "B.Cu" "B.Mask" "B.Paste")
			(net "P0V9")
			(options
				(clearance outline)
				(anchor circle)
			)
			(primitives
				(gr_poly
					(pts
						(arc
							(start 0.1524 0.127)
							(mid 0.137521 0.162921)
							(end 0.1016 0.1778)
						)
						(arc
							(start -0.1016 0.1778)
							(mid -0.137521 0.162921)
							(end -0.1524 0.127)
						)
						(arc
							(start -0.1524 -0.127)
							(mid -0.137521 -0.162921)
							(end -0.1016 -0.1778)
						)
						(arc
							(start 0.1016 -0.1778)
							(mid 0.137521 -0.162921)
							(end 0.1524 -0.127)
						)
					)
					(width 0)
					(fill yes)
				)
			)
		)
		(pad "2" smd custom
			(at 0 0.2794 180)
			(size 0.0762 0.0762)
			(layers "B.Cu" "B.Mask" "B.Paste")
			(net "GND")
			(options
				(clearance outline)
				(anchor circle)
			)
			(primitives
				(gr_poly
					(pts
						(arc
							(start 0.1524 0.127)
							(mid 0.137521 0.162921)
							(end 0.1016 0.1778)
						)
						(arc
							(start -0.1016 0.1778)
							(mid -0.137521 0.162921)
							(end -0.1524 0.127)
						)
						(arc
							(start -0.1524 -0.127)
							(mid -0.137521 -0.162921)
							(end -0.1016 -0.1778)
						)
						(arc
							(start 0.1016 -0.1778)
							(mid 0.137521 -0.162921)
							(end 0.1524 -0.127)
						)
					)
					(width 0)
					(fill yes)
				)
			)
		)
	)
	(footprint ""
		(layer "B.Cu")
		(at 170.942 -70.739)
		(property "Reference" "Q16"
			(at 0 0 0)
			(layer "B.SilkS")
			(hide yes)
			(effects
				(font
					(size 1.27 1.27)
				)
				(justify mirror)
			)
		)
		(property "Value" "SSM3K324R-GP"
			(at -0.127 -8.9662 0)
			(unlocked yes)
			(layer "B.Fab")
			(hide yes)
			(effects
				(font
					(size 1.016 1.016)
					(thickness 0.1524)
				)
				(justify mirror)
			)
		)
		(property "Device Type" "SOT23DGS2D4H35"
			(at -0.127 -10.4902 0)
			(unlocked yes)
			(layer "B.Fab")
			(hide yes)
			(effects
				(font
					(size 1.016 1.016)
					(thickness 0.1524)
				)
				(justify mirror)
			)
		)
		(duplicate_pad_numbers_are_jumpers no)
		(fp_line
			(start -1.651 -1.778)
			(end 1.651 -1.778)
			(stroke
				(width 0.1524)
				(type default)
			)
			(layer "B.SilkS")
		)
		(fp_line
			(start -1.651 1.778)
			(end -1.651 -1.778)
			(stroke
				(width 0.1524)
				(type default)
			)
			(layer "B.SilkS")
		)
		(fp_line
			(start 1.651 -1.778)
			(end 1.651 1.778)
			(stroke
				(width 0.1524)
				(type default)
			)
			(layer "B.SilkS")
		)
		(fp_line
			(start 1.651 1.778)
			(end -1.651 1.778)
			(stroke
				(width 0.1524)
				(type default)
			)
			(layer "B.SilkS")
		)
		(fp_poly
			(pts
				(xy 1.778 1.8796) (xy 1.778 -1.8796) (xy -1.778 -1.8796) (xy -1.778 1.8796)
			)
			(stroke
				(width 0)
				(type default)
			)
			(fill no)
			(layer "B.CrtYd")
		)
		(fp_poly
			(pts
				(xy 1.778 1.8796) (xy 1.778 -1.8796) (xy -1.778 -1.8796) (xy -1.778 1.8796)
			)
			(stroke
				(width 0)
				(type default)
			)
			(fill no)
			(layer "B.Fab")
		)
		(pad "D" smd custom
			(at 0 -0.9525 180)
			(size 0.1905 0.1905)
			(layers "B.Cu" "B.Mask" "B.Paste")
			(net "P3V3_STBY_Q15_R")
			(options
				(clearance outline)
				(anchor circle)
			)
			(primitives
				(gr_poly
					(pts
						(arc
							(start -0.1778 -0.5715)
							(mid -0.321484 -0.511984)
							(end -0.381 -0.3683)
						)
						(arc
							(start -0.381 0.3683)
							(mid -0.321484 0.511984)
							(end -0.1778 0.5715)
						)
						(arc
							(start 0.1778 0.5715)
							(mid 0.321484 0.511984)
							(end 0.381 0.3683)
						)
						(arc
							(start 0.381 -0.3683)
							(mid 0.321484 -0.511984)
							(end 0.1778 -0.5715)
						)
					)
					(width 0)
					(fill yes)
				)
			)
		)
		(pad "G" smd custom
			(at 0.98425 0.9525 180)
			(size 0.1905 0.1905)
			(layers "B.Cu" "B.Mask" "B.Paste")
			(net "IOC_VREF_SET")
			(options
				(clearance outline)
				(anchor circle)
			)
			(primitives
				(gr_poly
					(pts
						(arc
							(start -0.1778 -0.5715)
							(mid -0.321484 -0.511984)
							(end -0.381 -0.3683)
						)
						(arc
							(start -0.381 0.3683)
							(mid -0.321484 0.511984)
							(end -0.1778 0.5715)
						)
						(arc
							(start 0.1778 0.5715)
							(mid 0.321484 0.511984)
							(end 0.381 0.3683)
						)
						(arc
							(start 0.381 -0.3683)
							(mid 0.321484 -0.511984)
							(end 0.1778 -0.5715)
						)
					)
					(width 0)
					(fill yes)
				)
			)
		)
		(pad "S" smd custom
			(at -0.98425 0.9525 180)
			(size 0.1905 0.1905)
			(layers "B.Cu" "B.Mask" "B.Paste")
			(net "GND")
			(options
				(clearance outline)
				(anchor circle)
			)
			(primitives
				(gr_poly
					(pts
						(arc
							(start -0.1778 -0.5715)
							(mid -0.321484 -0.511984)
							(end -0.381 -0.3683)
						)
						(arc
							(start -0.381 0.3683)
							(mid -0.321484 0.511984)
							(end -0.1778 0.5715)
						)
						(arc
							(start 0.1778 0.5715)
							(mid 0.321484 0.511984)
							(end 0.381 0.3683)
						)
						(arc
							(start 0.381 -0.3683)
							(mid 0.321484 -0.511984)
							(end 0.1778 -0.5715)
						)
					)
					(width 0)
					(fill yes)
				)
			)
		)
	)
	(footprint ""
		(layer "B.Cu")
		(at 137.4648 -72.4408 -90)
		(property "Reference" "C12"
			(at 0 0 90)
			(layer "B.SilkS")
			(hide yes)
			(effects
				(font
					(size 1.27 1.27)
				)
				(justify mirror)
			)
		)
		(property "Value" "SCD01U16V1KX-GP"
			(at 2.8321 -1.7399 270)
			(unlocked yes)
			(layer "B.Fab")
			(hide yes)
			(effects
				(font
					(size 1.016 1.016)
					(thickness 0.1524)
				)
				(justify mirror)
			)
		)
		(property "Device Type" "C0201H13"
			(at 2.8321 -3.2639 270)
			(unlocked yes)
			(layer "B.Fab")
			(hide yes)
			(effects
				(font
					(size 1.016 1.016)
					(thickness 0.1524)
				)
				(justify mirror)
			)
		)
		(duplicate_pad_numbers_are_jumpers no)
		(fp_rect
			(start 0.2794 0.6477)
			(end -0.2794 -0.6477)
			(stroke
				(width 0)
				(type default)
			)
			(fill no)
			(layer "B.CrtYd")
		)
		(fp_rect
			(start 0.2794 0.6477)
			(end -0.2794 -0.6477)
			(stroke
				(width 0)
				(type default)
			)
			(fill no)
			(layer "B.Fab")
		)
		(pad "1" smd custom
			(at 0 -0.2794 90)
			(size 0.0762 0.0762)
			(layers "B.Cu" "B.Mask" "B.Paste")
			(net "PHY_DPB_TO_SCC_6_DN")
			(options
				(clearance outline)
				(anchor circle)
			)
			(primitives
				(gr_poly
					(pts
						(arc
							(start 0.1524 0.127)
							(mid 0.137521 0.162921)
							(end 0.1016 0.1778)
						)
						(arc
							(start -0.1016 0.1778)
							(mid -0.137521 0.162921)
							(end -0.1524 0.127)
						)
						(arc
							(start -0.1524 -0.127)
							(mid -0.137521 -0.162921)
							(end -0.1016 -0.1778)
						)
						(arc
							(start 0.1016 -0.1778)
							(mid 0.137521 -0.162921)
							(end 0.1524 -0.127)
						)
					)
					(width 0)
					(fill yes)
				)
			)
		)
		(pad "2" smd custom
			(at 0 0.2794 90)
			(size 0.0762 0.0762)
			(layers "B.Cu" "B.Mask" "B.Paste")
			(net "PHY_DPB_TO_SCC_C_6_DN")
			(options
				(clearance outline)
				(anchor circle)
			)
			(primitives
				(gr_poly
					(pts
						(arc
							(start 0.1524 0.127)
							(mid 0.137521 0.162921)
							(end 0.1016 0.1778)
						)
						(arc
							(start -0.1016 0.1778)
							(mid -0.137521 0.162921)
							(end -0.1524 0.127)
						)
						(arc
							(start -0.1524 -0.127)
							(mid -0.137521 -0.162921)
							(end -0.1016 -0.1778)
						)
						(arc
							(start 0.1016 -0.1778)
							(mid 0.137521 -0.162921)
							(end 0.1524 -0.127)
						)
					)
					(width 0)
					(fill yes)
				)
			)
		)
	)
)
